# SCM (Grand Teton) — schematic netlist excerpt (pin names and nets, part order shuffled) for the footprints in the layout excerpt that follows; sources: Cadence DE-HDL packaged netlist, KiCad conversion of 12092022_DA0F0TMDCD0_F0T_Management_Board_D_brd_V3_OCP.brd

R506  Q_RES  100 1% EMPTY  pkg 0402LF  page 48 : A = FM_BMC_DEBUG_SW_N ; B = GND
D8  Q_LED  IC  pkg SMLF  page 13 : A = BMC_HEARTBEAT_R_N ; C = BMC_HEARTBEAT_N

(kicad_pcb
	(version 20260206)
	(generator "pcbnew")
	(generator_version "10.0")
	(general
		(thickness 1.6)
		(legacy_teardrops no)
	)
	(paper "A4")
	(title_block
		(title "12092022_DA0F0TMDCD0_F0T_Management_Board_D_brd_V3_OCP.brd")
		(comment 1 "Grand Teton / footprints 690-691 of 1440")
	)
	(layers
		(0 "F.Cu" signal "TOP")
		(4 "In1.Cu" signal "GND")
		(6 "In2.Cu" signal "IN1")
		(8 "In3.Cu" signal "GND1")
		(10 "In4.Cu" signal "IN2")
		(12 "In5.Cu" signal "VCC")
		(14 "In6.Cu" signal "VCC1")
		(16 "In7.Cu" signal "IN3")
		(18 "In8.Cu" signal "GND2")
		(20 "In9.Cu" signal "IN4")
		(22 "In10.Cu" signal "GND3")
		(2 "B.Cu" signal "BOTTOM")
		(9 "F.Adhes" user "F.Adhesive")
		(11 "B.Adhes" user "B.Adhesive")
		(13 "F.Paste" user "Package Geometry/Pastemask Top")
		(15 "B.Paste" user "Package Geometry/Pastemask Bottom")
		(5 "F.SilkS" user "Ref Des/Silkscreen Top")
		(7 "B.SilkS" user "Ref Des/Silkscreen Bottom")
		(1 "F.Mask" user "Board Geometry/Soldermask Top")
		(3 "B.Mask" user "Board Geometry/Soldermask Bottom")
		(17 "Dwgs.User" user "User.Drawings")
		(19 "Cmts.User" user "User.Comments")
		(21 "Eco1.User" user "User.Eco1")
		(23 "Eco2.User" user "User.Eco2")
		(25 "Edge.Cuts" user "Board Geometry/Outline")
		(27 "Margin" user)
		(31 "F.CrtYd" user "Package Geometry/Place Bound Top")
		(29 "B.CrtYd" user "Package Geometry/Place Bound Bottom")
		(35 "F.Fab" user "Ref Des/Assembly Top")
		(33 "B.Fab" user "Ref Des/Assembly Bottom")
	)
	(footprint ""
		(layer "F.Cu")
		(at 63.246 -79.629)
		(property "Reference" "R506"
			(at 0 0 0)
			(layer "F.SilkS")
			(hide yes)
			(effects
				(font
					(size 1.27 1.27)
				)
			)
		)
		(property "Value" ""
			(at 0 0 0)
			(layer "F.Fab")
			(effects
				(font
					(size 1.27 1.27)
				)
			)
		)
		(duplicate_pad_numbers_are_jumpers no)
		(fp_line
			(start -0.7874 -0.4064)
			(end 0.7874 -0.4064)
			(stroke
				(width 0.1524)
				(type default)
			)
			(layer "F.SilkS")
		)
		(fp_line
			(start -0.7874 0.4064)
			(end -0.7874 -0.4064)
			(stroke
				(width 0.1524)
				(type default)
			)
			(layer "F.SilkS")
		)
		(fp_line
			(start 0.7874 -0.4064)
			(end 0.7874 0.4064)
			(stroke
				(width 0.1524)
				(type default)
			)
			(layer "F.SilkS")
		)
		(fp_line
			(start 0.7874 0.4064)
			(end -0.7874 0.4064)
			(stroke
				(width 0.1524)
				(type default)
			)
			(layer "F.SilkS")
		)
		(fp_line
			(start -0.67945 -0.305054)
			(end -0.12065 -0.305054)
			(stroke
				(width 0.1)
				(type default)
			)
			(layer "F.Fab")
		)
		(fp_line
			(start -0.67945 0.3048)
			(end -0.67945 -0.305054)
			(stroke
				(width 0.1)
				(type default)
			)
			(layer "F.Fab")
		)
		(fp_line
			(start -0.12065 -0.305054)
			(end -0.12065 -0.2794)
			(stroke
				(width 0.1)
				(type default)
			)
			(layer "F.Fab")
		)
		(fp_line
			(start -0.12065 -0.2794)
			(end 0.12065 -0.2794)
			(stroke
				(width 0.1)
				(type default)
			)
			(layer "F.Fab")
		)
		(fp_line
			(start -0.12065 0.2794)
			(end -0.12065 0.3048)
			(stroke
				(width 0.1)
				(type default)
			)
			(layer "F.Fab")
		)
		(fp_line
			(start -0.12065 0.3048)
			(end -0.67945 0.3048)
			(stroke
				(width 0.1)
				(type default)
			)
			(layer "F.Fab")
		)
		(fp_line
			(start 0.120396 0.2794)
			(end -0.12065 0.2794)
			(stroke
				(width 0.1)
				(type default)
			)
			(layer "F.Fab")
		)
		(fp_line
			(start 0.120396 0.3048)
			(end 0.120396 0.2794)
			(stroke
				(width 0.1)
				(type default)
			)
			(layer "F.Fab")
		)
		(fp_line
			(start 0.12065 -0.3048)
			(end 0.67945 -0.3048)
			(stroke
				(width 0.1)
				(type default)
			)
			(layer "F.Fab")
		)
		(fp_line
			(start 0.12065 -0.2794)
			(end 0.12065 -0.3048)
			(stroke
				(width 0.1)
				(type default)
			)
			(layer "F.Fab")
		)
		(fp_line
			(start 0.67945 -0.3048)
			(end 0.67945 0.3048)
			(stroke
				(width 0.1)
				(type default)
			)
			(layer "F.Fab")
		)
		(fp_line
			(start 0.67945 0.3048)
			(end 0.120396 0.3048)
			(stroke
				(width 0.1)
				(type default)
			)
			(layer "F.Fab")
		)
		(pad "1" smd circle
			(at -0.40005 0)
			(size 0 0)
			(layers "F.Cu" "F.Mask" "F.Paste")
			(net "FM_BMC_DEBUG_SW_N")
		)
		(pad "2" smd circle
			(at 0.40005 0)
			(size 0 0)
			(layers "F.Cu" "F.Mask" "F.Paste")
			(net "GND")
		)
	)
	(footprint ""
		(layer "F.Cu")
		(at 44.196 -67.7672)
		(property "Reference" "D8"
			(at -3.470656 -0.119634 0)
			(unlocked yes)
			(layer "F.SilkS")
			(effects
				(font
					(size 0.7874 0.5842)
					(thickness 0.1524)
				)
				(justify left)
			)
		)
		(property "Value" ""
			(at 0 0 0)
			(layer "F.Fab")
			(effects
				(font
					(size 1.27 1.27)
				)
			)
		)
		(duplicate_pad_numbers_are_jumpers no)
		(fp_line
			(start -1.3208 -0.5588)
			(end 1.3208 -0.5588)
			(stroke
				(width 0.1524)
				(type default)
			)
			(layer "F.SilkS")
		)
		(fp_line
			(start -1.3208 0.5588)
			(end -1.3208 -0.5588)
			(stroke
				(width 0.1524)
				(type default)
			)
			(layer "F.SilkS")
		)
		(fp_line
			(start 1.3208 -0.5588)
			(end 1.3208 0.5588)
			(stroke
				(width 0.1524)
				(type default)
			)
			(layer "F.SilkS")
		)
		(fp_line
			(start 1.3208 0.5588)
			(end -1.3208 0.5588)
			(stroke
				(width 0.1524)
				(type default)
			)
			(layer "F.SilkS")
		)
		(fp_line
			(start 1.4732 -0.5588)
			(end 1.4732 0.5588)
			(stroke
				(width 0.1524)
				(type default)
			)
			(layer "F.SilkS")
		)
		(fp_line
			(start 1.6256 0.5588)
			(end 1.6256 -0.5588)
			(stroke
				(width 0.1524)
				(type default)
			)
			(layer "F.SilkS")
		)
		(fp_line
			(start 1.778 -0.5588)
			(end 1.3208 -0.5588)
			(stroke
				(width 0.1524)
				(type default)
			)
			(layer "F.SilkS")
		)
		(fp_line
			(start 1.778 -0.5588)
			(end 1.778 0.5588)
			(stroke
				(width 0.1524)
				(type default)
			)
			(layer "F.SilkS")
		)
		(fp_line
			(start 1.778 0.5588)
			(end 1.3208 0.5588)
			(stroke
				(width 0.1524)
				(type default)
			)
			(layer "F.SilkS")
		)
		(fp_line
			(start -1.235964 -0.508)
			(end -1.235964 0.508)
			(stroke
				(width 0.1)
				(type default)
			)
			(layer "F.Fab")
		)
		(fp_line
			(start -1.235964 0.508)
			(end -1.1684 0.508)
			(stroke
				(width 0.1)
				(type default)
			)
			(layer "F.Fab")
		)
		(fp_line
			(start -1.1684 -0.508)
			(end -1.235964 -0.508)
			(stroke
				(width 0.1)
				(type default)
			)
			(layer "F.Fab")
		)
		(fp_line
			(start -1.1684 0.508)
			(end 1.1684 0.508)
			(stroke
				(width 0.1)
				(type default)
			)
			(layer "F.Fab")
		)
		(fp_line
			(start 1.1684 -0.508)
			(end -1.1684 -0.508)
			(stroke
				(width 0.1)
				(type default)
			)
			(layer "F.Fab")
		)
		(fp_line
			(start 1.1684 0.508)
			(end 1.236726 0.508)
			(stroke
				(width 0.1)
				(type default)
			)
			(layer "F.Fab")
		)
		(fp_line
			(start 1.236726 -0.508)
			(end 1.1684 -0.508)
			(stroke
				(width 0.1)
				(type default)
			)
			(layer "F.Fab")
		)
		(fp_line
			(start 1.236726 0.508)
			(end 1.236726 -0.508)
			(stroke
				(width 0.1)
				(type default)
			)
			(layer "F.Fab")
		)
		(fp_text user "+"
			(at -2.286 -1.06045 0)
			(unlocked yes)
			(layer "F.SilkS")
			(effects
				(font
					(size 1.905 1.4224)
					(thickness 0.1524)
				)
				(justify left)
			)
		)
		(fp_text user "-"
			(at 2.00025 0.7112 90)
			(unlocked yes)
			(layer "F.SilkS")
			(effects
				(font
					(size 1.905 1.4224)
					(thickness 0.1524)
				)
				(justify left)
			)
		)
		(fp_text user "+"
			(at -2.5654 -0.24765 0)
			(unlocked yes)
			(layer "F.Fab")
			(effects
				(font
					(size 1.905 1.4224)
					(thickness 0.1524)
				)
				(justify left)
			)
		)
		(fp_text user "-"
			(at 1.524 -0.24765 0)
			(unlocked yes)
			(layer "F.Fab")
			(effects
				(font
					(size 1.905 1.4224)
					(thickness 0.1524)
				)
				(justify left)
			)
		)
		(pad "A" smd rect
			(at -0.750062 0)
			(size 0.8128 0.8128)
			(layers "F.Cu" "F.Mask" "F.Paste")
			(net "BMC_HEARTBEAT_R_N")
		)
		(pad "C" smd rect
			(at 0.750062 0)
			(size 0.8128 0.8128)
			(layers "F.Cu" "F.Mask" "F.Paste")
			(net "BMC_HEARTBEAT_N")
		)
	)
)
